(kicad_pcb
	(version 20260206)
	(generator "pcbnew")
	(generator_version "10.0")
	(general
		(thickness 1.6)
		(legacy_teardrops no)
	)
	(paper "A4")
	(title_block
		(title "peb — Lightning_PEB_BRD.brd")
		(comment 1 "Lightning (Wiwynn / Facebook NVMe JBOF) / footprints 1133-1138 of 2563")
	)
	(layers
		(0 "F.Cu" signal "TOP")
		(4 "In1.Cu" signal "L2GND")
		(6 "In2.Cu" signal "L3")
		(8 "In3.Cu" signal "L4VCC")
		(10 "In4.Cu" signal "L5VCC")
		(12 "In5.Cu" signal "L6")
		(14 "In6.Cu" signal "L7GND")
		(2 "B.Cu" signal "BOTTOM")
		(9 "F.Adhes" user "F.Adhesive")
		(11 "B.Adhes" user "B.Adhesive")
		(13 "F.Paste" user "Package Geometry/Pastemask Top")
		(15 "B.Paste" user "Package Geometry/Pastemask Bottom")
		(5 "F.SilkS" user "Ref Des/Silkscreen Top")
		(7 "B.SilkS" user "Ref Des/Silkscreen Bottom")
		(1 "F.Mask" user "Board Geometry/Soldermask Top")
		(3 "B.Mask" user "Board Geometry/Soldermask Bottom")
		(17 "Dwgs.User" user "User.Drawings")
		(19 "Cmts.User" user "User.Comments")
		(21 "Eco1.User" user "User.Eco1")
		(23 "Eco2.User" user "User.Eco2")
		(25 "Edge.Cuts" user "Board Geometry/Outline")
		(27 "Margin" user)
		(31 "F.CrtYd" user "Package Geometry/Place Bound Top")
		(29 "B.CrtYd" user "Package Geometry/Place Bound Bottom")
		(35 "F.Fab" user "Ref Des/Assembly Top")
		(33 "B.Fab" user "Ref Des/Assembly Bottom")
	)
	(footprint ""
		(layer "F.Cu")
		(at 311.008014 -212.420454 180)
		(property "Reference" "C73"
			(at 0 0 180)
			(layer "F.SilkS")
			(hide yes)
			(effects
				(font
					(size 1.27 1.27)
				)
			)
		)
		(property "Value" "SCD22U10V2KX-1GP"
			(at 1.1811 -2.7051 180)
			(unlocked yes)
			(layer "F.Fab")
			(hide yes)
			(effects
				(font
					(size 1.016 1.016)
					(thickness 0.1524)
				)
			)
		)
		(property "Device Type" "C402H22"
			(at 1.1811 -4.2291 180)
			(unlocked yes)
			(layer "F.Fab")
			(hide yes)
			(effects
				(font
					(size 1.016 1.016)
					(thickness 0.1524)
				)
			)
		)
		(duplicate_pad_numbers_are_jumpers no)
		(fp_rect
			(start -0.4318 0.9525)
			(end 0.4318 -0.9525)
			(stroke
				(width 0)
				(type default)
			)
			(fill no)
			(layer "F.CrtYd")
		)
		(fp_rect
			(start -0.4318 0.9525)
			(end 0.4318 -0.9525)
			(stroke
				(width 0)
				(type default)
			)
			(fill no)
			(layer "F.Fab")
		)
		(pad "1" smd custom
			(at 0 -0.4445 180)
			(size 0.1524 0.1524)
			(layers "F.Cu" "F.Mask" "F.Paste")
			(net "PCIE_TX_CAP_N25")
			(options
				(clearance outline)
				(anchor circle)
			)
			(primitives
				(gr_poly
					(pts
						(arc
							(start 0.3048 -0.2032)
							(mid 0.275042 -0.275042)
							(end 0.2032 -0.3048)
						)
						(arc
							(start -0.2032 -0.3048)
							(mid -0.275042 -0.275042)
							(end -0.3048 -0.2032)
						)
						(arc
							(start -0.3048 0.2032)
							(mid -0.275042 0.275042)
							(end -0.2032 0.3048)
						)
						(arc
							(start 0.2032 0.3048)
							(mid 0.275042 0.275042)
							(end 0.3048 0.2032)
						)
					)
					(width 0)
					(fill yes)
				)
			)
		)
		(pad "2" smd custom
			(at 0 0.4445 180)
			(size 0.1524 0.1524)
			(layers "F.Cu" "F.Mask" "F.Paste")
			(net "PCIE_TX_N25")
			(options
				(clearance outline)
				(anchor circle)
			)
			(primitives
				(gr_poly
					(pts
						(arc
							(start 0.3048 -0.2032)
							(mid 0.275042 -0.275042)
							(end 0.2032 -0.3048)
						)
						(arc
							(start -0.2032 -0.3048)
							(mid -0.275042 -0.275042)
							(end -0.3048 -0.2032)
						)
						(arc
							(start -0.3048 0.2032)
							(mid -0.275042 0.275042)
							(end -0.2032 0.3048)
						)
						(arc
							(start 0.2032 0.3048)
							(mid 0.275042 0.275042)
							(end 0.3048 0.2032)
						)
					)
					(width 0)
					(fill yes)
				)
			)
		)
	)
	(footprint ""
		(layer "F.Cu")
		(at 181.63794 -13.156184 -90)
		(property "Reference" "R292"
			(at 0 0 270)
			(layer "F.SilkS")
			(hide yes)
			(effects
				(font
					(size 1.27 1.27)
				)
			)
		)
		(property "Value" "0R2J-2-GP"
			(at 0.064008 -3.993896 270)
			(unlocked yes)
			(layer "F.Fab")
			(hide yes)
			(effects
				(font
					(size 1.016 1.016)
					(thickness 0.1524)
				)
			)
		)
		(property "Device Type" "R402H16"
			(at 0.064008 -5.517896 270)
			(unlocked yes)
			(layer "F.Fab")
			(hide yes)
			(effects
				(font
					(size 1.016 1.016)
					(thickness 0.1524)
				)
			)
		)
		(duplicate_pad_numbers_are_jumpers no)
		(fp_line
			(start -0.508 -0.9398)
			(end -0.508 0.9398)
			(stroke
				(width 0.1524)
				(type default)
			)
			(layer "F.SilkS")
		)
		(fp_line
			(start 0.508 -0.9398)
			(end -0.508 -0.9398)
			(stroke
				(width 0.1524)
				(type default)
			)
			(layer "F.SilkS")
		)
		(fp_rect
			(start -0.508 0.9398)
			(end 0.508 -0.9398)
			(stroke
				(width 0)
				(type default)
			)
			(fill no)
			(layer "F.CrtYd")
		)
		(fp_rect
			(start -0.508 0.9398)
			(end 0.508 -0.9398)
			(stroke
				(width 0)
				(type default)
			)
			(fill no)
			(layer "F.Fab")
		)
		(pad "1" smd custom
			(at 0 -0.4445 270)
			(size 0.1397 0.1397)
			(layers "F.Cu" "F.Mask" "F.Paste")
			(net "MINISAS_CN15_D_I2C_INT#")
			(options
				(clearance outline)
				(anchor circle)
			)
			(primitives
				(gr_poly
					(pts
						(arc
							(start -0.1778 -0.2794)
							(mid -0.249642 -0.249642)
							(end -0.2794 -0.1778)
						)
						(arc
							(start -0.2794 0.1778)
							(mid -0.249642 0.249642)
							(end -0.1778 0.2794)
						)
						(arc
							(start 0.1778 0.2794)
							(mid 0.249642 0.249642)
							(end 0.2794 0.1778)
						)
						(arc
							(start 0.2794 -0.1778)
							(mid 0.249642 -0.249642)
							(end 0.1778 -0.2794)
						)
					)
					(width 0)
					(fill yes)
				)
			)
		)
		(pad "2" smd custom
			(at 0 0.4445 270)
			(size 0.1397 0.1397)
			(layers "F.Cu" "F.Mask" "F.Paste")
			(net "CLK_N_4")
			(options
				(clearance outline)
				(anchor circle)
			)
			(primitives
				(gr_poly
					(pts
						(arc
							(start -0.1778 -0.2794)
							(mid -0.249642 -0.249642)
							(end -0.2794 -0.1778)
						)
						(arc
							(start -0.2794 0.1778)
							(mid -0.249642 0.249642)
							(end -0.1778 0.2794)
						)
						(arc
							(start 0.1778 0.2794)
							(mid 0.249642 0.249642)
							(end 0.2794 0.1778)
						)
						(arc
							(start 0.2794 -0.1778)
							(mid 0.249642 -0.249642)
							(end 0.1778 -0.2794)
						)
					)
					(width 0)
					(fill yes)
				)
			)
		)
	)
	(footprint ""
		(layer "F.Cu")
		(at 133.2103 -33.54324)
		(property "Reference" "C385"
			(at 0 0 0)
			(layer "F.SilkS")
			(hide yes)
			(effects
				(font
					(size 1.27 1.27)
				)
			)
		)
		(property "Value" "SCD22U10V2KX-1GP"
			(at 1.1811 -2.7051 0)
			(unlocked yes)
			(layer "F.Fab")
			(hide yes)
			(effects
				(font
					(size 1.016 1.016)
					(thickness 0.1524)
				)
			)
		)
		(property "Device Type" "C402H22"
			(at 1.1811 -4.2291 0)
			(unlocked yes)
			(layer "F.Fab")
			(hide yes)
			(effects
				(font
					(size 1.016 1.016)
					(thickness 0.1524)
				)
			)
		)
		(duplicate_pad_numbers_are_jumpers no)
		(fp_rect
			(start -0.4318 0.9525)
			(end 0.4318 -0.9525)
			(stroke
				(width 0)
				(type default)
			)
			(fill no)
			(layer "F.CrtYd")
		)
		(fp_rect
			(start -0.4318 0.9525)
			(end 0.4318 -0.9525)
			(stroke
				(width 0)
				(type default)
			)
			(fill no)
			(layer "F.Fab")
		)
		(pad "1" smd custom
			(at 0 -0.4445)
			(size 0.1524 0.1524)
			(layers "F.Cu" "F.Mask" "F.Paste")
			(net "PCIE_TX_CAP_P82")
			(options
				(clearance outline)
				(anchor circle)
			)
			(primitives
				(gr_poly
					(pts
						(arc
							(start 0.3048 -0.2032)
							(mid 0.275042 -0.275042)
							(end 0.2032 -0.3048)
						)
						(arc
							(start -0.2032 -0.3048)
							(mid -0.275042 -0.275042)
							(end -0.3048 -0.2032)
						)
						(arc
							(start -0.3048 0.2032)
							(mid -0.275042 0.275042)
							(end -0.2032 0.3048)
						)
						(arc
							(start 0.2032 0.3048)
							(mid 0.275042 0.275042)
							(end 0.3048 0.2032)
						)
					)
					(width 0)
					(fill yes)
				)
			)
		)
		(pad "2" smd custom
			(at 0 0.4445)
			(size 0.1524 0.1524)
			(layers "F.Cu" "F.Mask" "F.Paste")
			(net "PCIE_TX_P82")
			(options
				(clearance outline)
				(anchor circle)
			)
			(primitives
				(gr_poly
					(pts
						(arc
							(start 0.3048 -0.2032)
							(mid 0.275042 -0.275042)
							(end 0.2032 -0.3048)
						)
						(arc
							(start -0.2032 -0.3048)
							(mid -0.275042 -0.275042)
							(end -0.3048 -0.2032)
						)
						(arc
							(start -0.3048 0.2032)
							(mid -0.275042 0.275042)
							(end -0.2032 0.3048)
						)
						(arc
							(start 0.2032 0.3048)
							(mid 0.275042 0.275042)
							(end 0.3048 0.2032)
						)
					)
					(width 0)
					(fill yes)
				)
			)
		)
	)
	(footprint ""
		(layer "F.Cu")
		(at 50.8762 -50.3174 180)
		(property "Reference" "R500"
			(at 0 0 180)
			(layer "F.SilkS")
			(hide yes)
			(effects
				(font
					(size 1.27 1.27)
				)
			)
		)
		(property "Value" "3K3R2F-2-GP"
			(at 0.064008 -3.993896 180)
			(unlocked yes)
			(layer "F.Fab")
			(hide yes)
			(effects
				(font
					(size 1.016 1.016)
					(thickness 0.1524)
				)
			)
		)
		(property "Device Type" "R402H16"
			(at 0.064008 -5.517896 180)
			(unlocked yes)
			(layer "F.Fab")
			(hide yes)
			(effects
				(font
					(size 1.016 1.016)
					(thickness 0.1524)
				)
			)
		)
		(duplicate_pad_numbers_are_jumpers no)
		(fp_line
			(start 0.508 -0.9398)
			(end -0.508 -0.9398)
			(stroke
				(width 0.1524)
				(type default)
			)
			(layer "F.SilkS")
		)
		(fp_line
			(start -0.508 -0.9398)
			(end -0.508 0.9398)
			(stroke
				(width 0.1524)
				(type default)
			)
			(layer "F.SilkS")
		)
		(fp_rect
			(start -0.508 0.9398)
			(end 0.508 -0.9398)
			(stroke
				(width 0)
				(type default)
			)
			(fill no)
			(layer "F.CrtYd")
		)
		(fp_rect
			(start -0.508 0.9398)
			(end 0.508 -0.9398)
			(stroke
				(width 0)
				(type default)
			)
			(fill no)
			(layer "F.Fab")
		)
		(pad "1" smd custom
			(at 0 -0.4445 180)
			(size 0.1397 0.1397)
			(layers "F.Cu" "F.Mask" "F.Paste")
			(net "P3V3_STBY")
			(options
				(clearance outline)
				(anchor circle)
			)
			(primitives
				(gr_poly
					(pts
						(arc
							(start -0.1778 -0.2794)
							(mid -0.249642 -0.249642)
							(end -0.2794 -0.1778)
						)
						(arc
							(start -0.2794 0.1778)
							(mid -0.249642 0.249642)
							(end -0.1778 0.2794)
						)
						(arc
							(start 0.1778 0.2794)
							(mid 0.249642 0.249642)
							(end 0.2794 0.1778)
						)
						(arc
							(start 0.2794 -0.1778)
							(mid 0.249642 -0.249642)
							(end 0.1778 -0.2794)
						)
					)
					(width 0)
					(fill yes)
				)
			)
		)
		(pad "2" smd custom
			(at 0 0.4445 180)
			(size 0.1397 0.1397)
			(layers "F.Cu" "F.Mask" "F.Paste")
			(net "U44_HOLD_N")
			(options
				(clearance outline)
				(anchor circle)
			)
			(primitives
				(gr_poly
					(pts
						(arc
							(start -0.1778 -0.2794)
							(mid -0.249642 -0.249642)
							(end -0.2794 -0.1778)
						)
						(arc
							(start -0.2794 0.1778)
							(mid -0.249642 0.249642)
							(end -0.1778 0.2794)
						)
						(arc
							(start 0.1778 0.2794)
							(mid 0.249642 0.249642)
							(end 0.2794 0.1778)
						)
						(arc
							(start 0.2794 -0.1778)
							(mid 0.249642 -0.249642)
							(end 0.1778 -0.2794)
						)
					)
					(width 0)
					(fill yes)
				)
			)
		)
	)
	(footprint ""
		(layer "F.Cu")
		(at 7.2136 -70.9676 -90)
		(property "Reference" "X11"
			(at 0 0 270)
			(layer "F.SilkS")
			(hide yes)
			(effects
				(font
					(size 1.27 1.27)
				)
			)
		)
		(property "Value" "XTAL-25MHZ-96GP"
			(at 0 -7.5692 270)
			(unlocked yes)
			(layer "F.Fab")
			(hide yes)
			(effects
				(font
					(size 1.016 1.016)
					(thickness 0.1524)
				)
			)
		)
		(property "Device Type" "SMD49-4H56"
			(at 0 -9.0932 270)
			(unlocked yes)
			(layer "F.Fab")
			(hide yes)
			(effects
				(font
					(size 1.016 1.016)
					(thickness 0.1524)
				)
			)
		)
		(duplicate_pad_numbers_are_jumpers no)
		(fp_line
			(start -3.6322 1.8542)
			(end -3.6322 -1.8542)
			(stroke
				(width 0.1524)
				(type default)
			)
			(layer "F.SilkS")
		)
		(fp_line
			(start 3.6322 1.8542)
			(end -3.6322 1.8542)
			(stroke
				(width 0.1524)
				(type default)
			)
			(layer "F.SilkS")
		)
		(fp_line
			(start -3.6322 -1.8542)
			(end 3.6322 -1.8542)
			(stroke
				(width 0.1524)
				(type default)
			)
			(layer "F.SilkS")
		)
		(fp_line
			(start 3.6322 -1.8542)
			(end 3.6322 1.8542)
			(stroke
				(width 0.1524)
				(type default)
			)
			(layer "F.SilkS")
		)
		(fp_poly
			(pts
				(xy -3.8862 2.1082) (xy 3.8862 2.1082) (xy 3.8862 -2.1082) (xy -3.8862 -2.1082)
			)
			(stroke
				(width 0)
				(type default)
			)
			(fill no)
			(layer "F.CrtYd")
		)
		(fp_poly
			(pts
				(xy -3.8862 -2.1082) (xy 3.8862 -2.1082) (xy 3.8862 2.1082) (xy -3.8862 2.1082)
			)
			(stroke
				(width 0)
				(type default)
			)
			(fill no)
			(layer "F.Fab")
		)
		(pad "1" smd rect
			(at -2.16535 0 270)
			(size 2.4384 2.2606)
			(layers "F.Cu" "F.Mask" "F.Paste")
			(net "XTAL_OUT_I210_R")
		)
		(pad "2" smd rect
			(at 2.16535 0 270)
			(size 2.4384 2.2606)
			(layers "F.Cu" "F.Mask" "F.Paste")
			(net "XTAL_IN_I210_R")
		)
		(zone
			(layer "F.Cu")
			(hatch none 0.5)
			(connect_pads
				(clearance 0)
			)
			(min_thickness 0.25)
			(keepout
				(tracks not_allowed)
				(vias allowed)
				(pads allowed)
				(copperpour not_allowed)
				(footprints allowed)
			)
			(placement
				(enabled no)
				(sheetname "")
			)
			(fill
				(thermal_gap 0.5)
				(thermal_bridge_width 0.5)
				(island_removal_mode 0)
			)
			(polygon
				(pts
					(xy 5.4356 -74.35215) (xy 5.4356 -73.13295) (xy 6.0833 -73.13295) (xy 6.0833 -74.35215)
				)
			)
		)
		(zone
			(layer "F.Cu")
			(hatch none 0.5)
			(connect_pads
				(clearance 0)
			)
			(min_thickness 0.25)
			(keepout
				(tracks allowed)
				(vias not_allowed)
				(pads allowed)
				(copperpour not_allowed)
				(footprints allowed)
			)
			(placement
				(enabled no)
				(sheetname "")
			)
			(fill
				(thermal_gap 0.5)
				(thermal_bridge_width 0.5)
				(island_removal_mode 0)
			)
			(polygon
				(pts
					(xy 5.4356 -74.35215) (xy 5.4356 -73.13295) (xy 6.0833 -73.13295) (xy 6.0833 -74.35215)
				)
			)
		)
		(zone
			(layer "F.Cu")
			(hatch none 0.5)
			(connect_pads
				(clearance 0)
			)
			(min_thickness 0.25)
			(keepout
				(tracks not_allowed)
				(vias allowed)
				(pads allowed)
				(copperpour not_allowed)
				(footprints allowed)
			)
			(placement
				(enabled no)
				(sheetname "")
			)
			(fill
				(thermal_gap 0.5)
				(thermal_bridge_width 0.5)
				(island_removal_mode 0)
			)
			(polygon
				(pts
					(xy 5.4356 -68.80225) (xy 5.4356 -67.58305) (xy 6.0833 -67.58305) (xy 6.0833 -68.80225)
				)
			)
		)
		(zone
			(layer "F.Cu")
			(hatch none 0.5)
			(connect_pads
				(clearance 0)
			)
			(min_thickness 0.25)
			(keepout
				(tracks allowed)
				(vias not_allowed)
				(pads allowed)
				(copperpour not_allowed)
				(footprints allowed)
			)
			(placement
				(enabled no)
				(sheetname "")
			)
			(fill
				(thermal_gap 0.5)
				(thermal_bridge_width 0.5)
				(island_removal_mode 0)
			)
			(polygon
				(pts
					(xy 5.4356 -68.80225) (xy 5.4356 -67.58305) (xy 6.0833 -67.58305) (xy 6.0833 -68.80225)
				)
			)
		)
		(zone
			(layer "F.Cu")
			(hatch none 0.5)
			(connect_pads
				(clearance 0)
			)
			(min_thickness 0.25)
			(keepout
				(tracks allowed)
				(vias not_allowed)
				(pads allowed)
				(copperpour not_allowed)
				(footprints allowed)
			)
			(placement
				(enabled no)
				(sheetname "")
			)
			(fill
				(thermal_gap 0.5)
				(thermal_bridge_width 0.5)
				(island_removal_mode 0)
			)
			(polygon
				(pts
					(xy 8.3439 -74.35215) (xy 8.3439 -73.13295) (xy 8.9916 -73.1393) (xy 8.9916 -74.35215)
				)
			)
		)
		(zone
			(layer "F.Cu")
			(hatch none 0.5)
			(connect_pads
				(clearance 0)
			)
			(min_thickness 0.25)
			(keepout
				(tracks not_allowed)
				(vias allowed)
				(pads allowed)
				(copperpour not_allowed)
				(footprints allowed)
			)
			(placement
				(enabled no)
				(sheetname "")
			)
			(fill
				(thermal_gap 0.5)
				(thermal_bridge_width 0.5)
				(island_removal_mode 0)
			)
			(polygon
				(pts
					(xy 8.3439 -74.35215) (xy 8.3439 -73.13295) (xy 8.9916 -73.1393) (xy 8.9916 -74.35215)
				)
			)
		)
		(zone
			(layer "F.Cu")
			(hatch none 0.5)
			(connect_pads
				(clearance 0)
			)
			(min_thickness 0.25)
			(keepout
				(tracks not_allowed)
				(vias allowed)
				(pads allowed)
				(copperpour not_allowed)
				(footprints allowed)
			)
			(placement
				(enabled no)
				(sheetname "")
			)
			(fill
				(thermal_gap 0.5)
				(thermal_bridge_width 0.5)
				(island_removal_mode 0)
			)
			(polygon
				(pts
					(xy 8.3439 -68.80225) (xy 8.3439 -67.58305) (xy 8.9916 -67.58305) (xy 8.9916 -68.7959)
				)
			)
		)
		(zone
			(layer "F.Cu")
			(hatch none 0.5)
			(connect_pads
				(clearance 0)
			)
			(min_thickness 0.25)
			(keepout
				(tracks allowed)
				(vias not_allowed)
				(pads allowed)
				(copperpour not_allowed)
				(footprints allowed)
			)
			(placement
				(enabled no)
				(sheetname "")
			)
			(fill
				(thermal_gap 0.5)
				(thermal_bridge_width 0.5)
				(island_removal_mode 0)
			)
			(polygon
				(pts
					(xy 8.3439 -68.80225) (xy 8.3439 -67.58305) (xy 8.9916 -67.58305) (xy 8.9916 -68.7959)
				)
			)
		)
	)
	(footprint ""
		(layer "F.Cu")
		(at 56.515 -130.048 180)
		(property "Reference" "C192"
			(at 0 0 180)
			(layer "F.SilkS")
			(hide yes)
			(effects
				(font
					(size 1.27 1.27)
				)
			)
		)
		(property "Value" "SC1U10V2KX-4-GP"
			(at 1.1811 -2.7051 180)
			(unlocked yes)
			(layer "F.Fab")
			(hide yes)
			(effects
				(font
					(size 1.016 1.016)
					(thickness 0.1524)
				)
			)
		)
		(property "Device Type" "C402H22"
			(at 1.1811 -4.2291 180)
			(unlocked yes)
			(layer "F.Fab")
			(hide yes)
			(effects
				(font
					(size 1.016 1.016)
					(thickness 0.1524)
				)
			)
		)
		(duplicate_pad_numbers_are_jumpers no)
		(fp_rect
			(start -0.4318 0.9525)
			(end 0.4318 -0.9525)
			(stroke
				(width 0)
				(type default)
			)
			(fill no)
			(layer "F.CrtYd")
		)
		(fp_rect
			(start -0.4318 0.9525)
			(end 0.4318 -0.9525)
			(stroke
				(width 0)
				(type default)
			)
			(fill no)
			(layer "F.Fab")
		)
		(pad "1" smd custom
			(at 0 -0.4445 180)
			(size 0.1524 0.1524)
			(layers "F.Cu" "F.Mask" "F.Paste")
			(net "ADCAV33")
			(options
				(clearance outline)
				(anchor circle)
			)
			(primitives
				(gr_poly
					(pts
						(arc
							(start 0.3048 -0.2032)
							(mid 0.275042 -0.275042)
							(end 0.2032 -0.3048)
						)
						(arc
							(start -0.2032 -0.3048)
							(mid -0.275042 -0.275042)
							(end -0.3048 -0.2032)
						)
						(arc
							(start -0.3048 0.2032)
							(mid -0.275042 0.275042)
							(end -0.2032 0.3048)
						)
						(arc
							(start 0.2032 0.3048)
							(mid 0.275042 0.275042)
							(end 0.3048 0.2032)
						)
					)
					(width 0)
					(fill yes)
				)
			)
		)
		(pad "2" smd custom
			(at 0 0.4445 180)
			(size 0.1524 0.1524)
			(layers "F.Cu" "F.Mask" "F.Paste")
			(net "GND")
			(options
				(clearance outline)
				(anchor circle)
			)
			(primitives
				(gr_poly
					(pts
						(arc
							(start 0.3048 -0.2032)
							(mid 0.275042 -0.275042)
							(end 0.2032 -0.3048)
						)
						(arc
							(start -0.2032 -0.3048)
							(mid -0.275042 -0.275042)
							(end -0.3048 -0.2032)
						)
						(arc
							(start -0.3048 0.2032)
							(mid -0.275042 0.275042)
							(end -0.2032 0.3048)
						)
						(arc
							(start 0.2032 0.3048)
							(mid 0.275042 0.275042)
							(end 0.3048 0.2032)
						)
					)
					(width 0)
					(fill yes)
				)
			)
		)
	)
)
